# T6G (Grand Teton) — schematic netlist excerpt (pin names and nets, part order shuffled) for the footprints in the layout excerpt that follows; sources: Cadence DE-HDL packaged netlist, KiCad conversion of 04192023_DAF0TMB3IC0_F0TG_MB_C_brd_V02_OCP.brd

C345  Q_CAP  0.1UF 25V 10% EMPTY  pkg 0402  page 269 : A = P1V8_AUX_ENABLE ; B = GND
PR126  Q_RES  3.09K 1% CHIP  pkg 0402LF  page 207 : A = PVDD11_S3_P0_ADDR_CFG ; B = GND

(kicad_pcb
	(version 20260206)
	(generator "pcbnew")
	(generator_version "10.0")
	(general
		(thickness 1.6)
		(legacy_teardrops no)
	)
	(paper "A4")
	(title_block
		(title "04192023_DAF0TMB3IC0_F0TG_MB_C_brd_V02_OCP.brd")
		(comment 1 "Grand Teton / footprints 2729-2730 of 8354")
	)
	(layers
		(0 "F.Cu" signal "TOP")
		(4 "In1.Cu" signal "GND")
		(6 "In2.Cu" signal "IN1")
		(8 "In3.Cu" signal "GND1")
		(10 "In4.Cu" signal "IN2")
		(12 "In5.Cu" signal "GND2")
		(14 "In6.Cu" signal "IN3")
		(16 "In7.Cu" signal "GND3")
		(18 "In8.Cu" signal "VCC")
		(20 "In9.Cu" signal "VCC1")
		(22 "In10.Cu" signal "GND4")
		(24 "In11.Cu" signal "IN4")
		(26 "In12.Cu" signal "GND5")
		(28 "In13.Cu" signal "IN5")
		(30 "In14.Cu" signal "GND6")
		(32 "In15.Cu" signal "IN6")
		(34 "In16.Cu" signal "GND7")
		(2 "B.Cu" signal "BOTTOM")
		(9 "F.Adhes" user "F.Adhesive")
		(11 "B.Adhes" user "B.Adhesive")
		(13 "F.Paste" user "Package Geometry/Pastemask Top")
		(15 "B.Paste" user "Package Geometry/Pastemask Bottom")
		(5 "F.SilkS" user "Ref Des/Silkscreen Top")
		(7 "B.SilkS" user "Ref Des/Silkscreen Bottom")
		(1 "F.Mask" user "Board Geometry/Soldermask Top")
		(3 "B.Mask" user "Board Geometry/Soldermask Bottom")
		(17 "Dwgs.User" user "User.Drawings")
		(19 "Cmts.User" user "User.Comments")
		(21 "Eco1.User" user "User.Eco1")
		(23 "Eco2.User" user "User.Eco2")
		(25 "Edge.Cuts" user "Board Geometry/Outline")
		(27 "Margin" user)
		(31 "F.CrtYd" user "Package Geometry/Place Bound Top")
		(29 "B.CrtYd" user "Package Geometry/Place Bound Bottom")
		(35 "F.Fab" user "Ref Des/Assembly Top")
		(33 "B.Fab" user "Ref Des/Assembly Bottom")
	)
	(footprint ""
		(layer "F.Cu")
		(at 423.631868 -360.824018)
		(property "Reference" "PR126"
			(at 0 0 0)
			(layer "F.SilkS")
			(hide yes)
			(effects
				(font
					(size 1.27 1.27)
				)
			)
		)
		(property "Value" ""
			(at 0 0 0)
			(layer "F.Fab")
			(effects
				(font
					(size 1.27 1.27)
				)
			)
		)
		(duplicate_pad_numbers_are_jumpers no)
		(fp_line
			(start -0.7874 -0.4064)
			(end 0.7874 -0.4064)
			(stroke
				(width 0.1524)
				(type default)
			)
			(layer "F.SilkS")
		)
		(fp_line
			(start -0.7874 0.4064)
			(end -0.7874 -0.4064)
			(stroke
				(width 0.1524)
				(type default)
			)
			(layer "F.SilkS")
		)
		(fp_line
			(start 0.7874 -0.4064)
			(end 0.7874 0.4064)
			(stroke
				(width 0.1524)
				(type default)
			)
			(layer "F.SilkS")
		)
		(fp_line
			(start 0.7874 0.4064)
			(end -0.7874 0.4064)
			(stroke
				(width 0.1524)
				(type default)
			)
			(layer "F.SilkS")
		)
		(fp_line
			(start -0.67945 -0.305054)
			(end -0.12065 -0.305054)
			(stroke
				(width 0.1)
				(type default)
			)
			(layer "F.Fab")
		)
		(fp_line
			(start -0.67945 0.3048)
			(end -0.67945 -0.305054)
			(stroke
				(width 0.1)
				(type default)
			)
			(layer "F.Fab")
		)
		(fp_line
			(start -0.12065 -0.305054)
			(end -0.12065 -0.2794)
			(stroke
				(width 0.1)
				(type default)
			)
			(layer "F.Fab")
		)
		(fp_line
			(start -0.12065 -0.2794)
			(end 0.12065 -0.2794)
			(stroke
				(width 0.1)
				(type default)
			)
			(layer "F.Fab")
		)
		(fp_line
			(start -0.12065 0.2794)
			(end -0.12065 0.3048)
			(stroke
				(width 0.1)
				(type default)
			)
			(layer "F.Fab")
		)
		(fp_line
			(start -0.12065 0.3048)
			(end -0.67945 0.3048)
			(stroke
				(width 0.1)
				(type default)
			)
			(layer "F.Fab")
		)
		(fp_line
			(start 0.120396 0.2794)
			(end -0.12065 0.2794)
			(stroke
				(width 0.1)
				(type default)
			)
			(layer "F.Fab")
		)
		(fp_line
			(start 0.120396 0.3048)
			(end 0.120396 0.2794)
			(stroke
				(width 0.1)
				(type default)
			)
			(layer "F.Fab")
		)
		(fp_line
			(start 0.12065 -0.3048)
			(end 0.67945 -0.3048)
			(stroke
				(width 0.1)
				(type default)
			)
			(layer "F.Fab")
		)
		(fp_line
			(start 0.12065 -0.2794)
			(end 0.12065 -0.3048)
			(stroke
				(width 0.1)
				(type default)
			)
			(layer "F.Fab")
		)
		(fp_line
			(start 0.67945 -0.3048)
			(end 0.67945 0.3048)
			(stroke
				(width 0.1)
				(type default)
			)
			(layer "F.Fab")
		)
		(fp_line
			(start 0.67945 0.3048)
			(end 0.120396 0.3048)
			(stroke
				(width 0.1)
				(type default)
			)
			(layer "F.Fab")
		)
		(pad "1" smd circle
			(at -0.40005 0)
			(size 0 0)
			(layers "F.Cu" "F.Mask" "F.Paste")
			(net "PVDD11_S3_P0_ADDR_CFG")
		)
		(pad "2" smd circle
			(at 0.40005 0)
			(size 0 0)
			(layers "F.Cu" "F.Mask" "F.Paste")
			(net "GND")
		)
	)
	(footprint ""
		(layer "F.Cu")
		(at 215.585548 -133.600952 90)
		(property "Reference" "C345"
			(at 0 0 90)
			(layer "F.SilkS")
			(hide yes)
			(effects
				(font
					(size 1.27 1.27)
				)
			)
		)
		(property "Value" ""
			(at 0 0 90)
			(layer "F.Fab")
			(effects
				(font
					(size 1.27 1.27)
				)
			)
		)
		(duplicate_pad_numbers_are_jumpers no)
		(fp_line
			(start 0.7874 -0.4064)
			(end 0.7874 0.4064)
			(stroke
				(width 0.1524)
				(type default)
			)
			(layer "F.SilkS")
		)
		(fp_line
			(start -0.7874 -0.4064)
			(end 0.7874 -0.4064)
			(stroke
				(width 0.1524)
				(type default)
			)
			(layer "F.SilkS")
		)
		(fp_line
			(start 0.7874 0.4064)
			(end -0.7874 0.4064)
			(stroke
				(width 0.1524)
				(type default)
			)
			(layer "F.SilkS")
		)
		(fp_line
			(start -0.7874 0.4064)
			(end -0.7874 -0.4064)
			(stroke
				(width 0.1524)
				(type default)
			)
			(layer "F.SilkS")
		)
		(fp_line
			(start -0.12065 -0.305054)
			(end -0.12065 -0.2794)
			(stroke
				(width 0.1)
				(type default)
			)
			(layer "F.Fab")
		)
		(fp_line
			(start -0.67945 -0.305054)
			(end -0.12065 -0.305054)
			(stroke
				(width 0.1)
				(type default)
			)
			(layer "F.Fab")
		)
		(fp_line
			(start 0.67945 -0.3048)
			(end 0.67945 0.3048)
			(stroke
				(width 0.1)
				(type default)
			)
			(layer "F.Fab")
		)
		(fp_line
			(start 0.12065 -0.3048)
			(end 0.67945 -0.3048)
			(stroke
				(width 0.1)
				(type default)
			)
			(layer "F.Fab")
		)
		(fp_line
			(start 0.12065 -0.2794)
			(end 0.12065 -0.3048)
			(stroke
				(width 0.1)
				(type default)
			)
			(layer "F.Fab")
		)
		(fp_line
			(start -0.12065 -0.2794)
			(end 0.12065 -0.2794)
			(stroke
				(width 0.1)
				(type default)
			)
			(layer "F.Fab")
		)
		(fp_line
			(start 0.120396 0.2794)
			(end -0.12065 0.2794)
			(stroke
				(width 0.1)
				(type default)
			)
			(layer "F.Fab")
		)
		(fp_line
			(start -0.12065 0.2794)
			(end -0.12065 0.3048)
			(stroke
				(width 0.1)
				(type default)
			)
			(layer "F.Fab")
		)
		(fp_line
			(start 0.67945 0.3048)
			(end 0.120396 0.3048)
			(stroke
				(width 0.1)
				(type default)
			)
			(layer "F.Fab")
		)
		(fp_line
			(start 0.120396 0.3048)
			(end 0.120396 0.2794)
			(stroke
				(width 0.1)
				(type default)
			)
			(layer "F.Fab")
		)
		(fp_line
			(start -0.12065 0.3048)
			(end -0.67945 0.3048)
			(stroke
				(width 0.1)
				(type default)
			)
			(layer "F.Fab")
		)
		(fp_line
			(start -0.67945 0.3048)
			(end -0.67945 -0.305054)
			(stroke
				(width 0.1)
				(type default)
			)
			(layer "F.Fab")
		)
		(pad "1" smd circle
			(at -0.40005 0 90)
			(size 0 0)
			(layers "F.Cu" "F.Mask" "F.Paste")
			(net "P1V8_AUX_ENABLE")
		)
		(pad "2" smd circle
			(at 0.40005 0 90)
			(size 0 0)
			(layers "F.Cu" "F.Mask" "F.Paste")
			(net "GND")
		)
	)
)
